(kicad_pcb
	(version 20221018)
	(generator pcbnew)
	(general
    (thickness 1.7403)
  )
	(paper "A4")
	(title_block
    (title "Data Center RDIMM DDR4 Tester")
    (date "2024-09-30")
    (rev "1.2.4")
		(comment 9 "footprints 180-188 of 690")
	)
	(layers
    (0 "F.Cu" signal)
    (1 "In1.Cu" power)
    (2 "In2.Cu" signal)
    (3 "In3.Cu" power)
    (4 "In4.Cu" power)
    (5 "In5.Cu" signal)
    (6 "In6.Cu" power)
    (7 "In7.Cu" signal)
    (8 "In8.Cu" power)
    (9 "In9.Cu" signal)
    (10 "In10.Cu" power)
    (31 "B.Cu" signal)
    (32 "B.Adhes" user "B.Adhesive")
    (33 "F.Adhes" user "F.Adhesive")
    (34 "B.Paste" user)
    (35 "F.Paste" user)
    (36 "B.SilkS" user "B.Silkscreen")
    (37 "F.SilkS" user "F.Silkscreen")
    (38 "B.Mask" user)
    (39 "F.Mask" user)
    (40 "Dwgs.User" user "User.Drawings")
    (41 "Cmts.User" user "User.Comments")
    (42 "Eco1.User" user "User.Eco1")
    (43 "Eco2.User" user "User.Eco2")
    (44 "Edge.Cuts" user)
    (45 "Margin" user)
    (46 "B.CrtYd" user "B.Courtyard")
    (47 "F.CrtYd" user "F.Courtyard")
    (48 "B.Fab" user)
    (49 "F.Fab" user)
  )
	(footprint "data-center-rdimm-ddr4-tester-footprints:Testpoint_smd_1mm" (layer "F.Cu")
    (at 118.964728 72.190808)
    (property "Author" "Antmicro")
    (property "License" "Apache-2.0")
    (property "MPN" "")
    (property "Manufacturer" "")
    (property "Sheetfile" "fpga-banks-16-34.kicad_sch")
    (property "Sheetname" "FPGA banks 16-34")
    (property "ki_description" "Test Point 1mm")
    (attr exclude_from_pos_files)
    (fp_text reference "TP12" (at -1.764728 -0.630808) (layer "F.SilkS")
        (effects (font (size 0.7 0.7) (thickness 0.15)) (justify left bottom))
    )
    (fp_text value "TP_1mm_SMD" (at 0 1.4) (layer "F.Fab") hide
        (effects (font (size 0.7 0.7) (thickness 0.15)) (justify left bottom))
    )
    (fp_text user "License: Apache-2.0" (at -0.5 5.2) (layer "F.Fab") hide
        (effects (font (size 0.7 0.7) (thickness 0.15)) (justify left bottom))
    )
    (fp_text user "${REFERENCE}" (at -0.5 2.8) (layer "F.Fab") hide
        (effects (font (size 0.7 0.7) (thickness 0.15)) (justify left bottom))
    )
    (fp_text user "Author: Antmicro" (at -0.5 4) (layer "F.Fab") hide
        (effects (font (size 0.7 0.7) (thickness 0.15)) (justify left bottom))
    )
    (pad "1" smd circle (at 0 0) (size 1 1) (layers "F.Cu" "F.Mask")
      (net 666 "Net-(U8-EN)") (pinfunction "1") (pintype "passive"))
  )
	(footprint "data-center-rdimm-ddr4-tester-footprints:R_0402_1005Metric" (layer "F.Cu")
    (at 120.587128 74.106008)
    (descr "Resistor SMD 0402")
    (tags "resistor SMD 0402")
    (property "Author" "Antmicro")
    (property "License" "Apache-2.0")
    (property "MPN" "CR0402-FX-4701GLF")
    (property "Manufacturer" "Bourns")
    (property "Sheetfile" "fpga-banks-16-34.kicad_sch")
    (property "Sheetname" "FPGA banks 16-34")
    (property "Tolerance" "1%")
    (property "Val" "4k7")
    (property "ki_description" "4k7 resistor in 0402 package with 1% tolerance")
    (attr smd)
    (fp_text reference "R172" (at -3.707128 0.343992) (layer "F.SilkS")
        (effects (font (size 0.7 0.7) (thickness 0.15)) (justify left bottom))
    )
    (fp_text value "R_4k7_0402" (at 0 1.4) (layer "F.Fab") hide
        (effects (font (size 0.7 0.7) (thickness 0.15)) (justify left bottom))
    )
    (fp_text user "${REFERENCE}" (at -0.95 3.168) (layer "F.Fab") hide
        (effects (font (size 0.7 0.7) (thickness 0.15)) (justify left bottom))
    )
    (fp_text user "Author: Antmicro" (at -0.95 4.169) (layer "F.Fab") hide
        (effects (font (size 0.7 0.7) (thickness 0.15)) (justify left bottom))
    )
    (fp_text user "License: Apache-2.0" (at -0.95 5.169) (layer "F.Fab") hide
        (effects (font (size 0.7 0.7) (thickness 0.15)) (justify left bottom))
    )
    (fp_rect (start -0.93 -0.47) (end 0.93 0.47)
      (stroke (width 0.05) (type solid)) (fill none) (layer "F.CrtYd"))
    (fp_rect (start -0.5 -0.25) (end 0.5 0.25)
      (stroke (width 0.15) (type solid)) (fill none) (layer "F.Fab"))
    (pad "1" smd roundrect (at -0.485 0) (size 0.59 0.64) (layers "F.Cu" "F.Paste" "F.Mask") (roundrect_rratio 0.25)
      (net 143 "3V3_SYS") (pintype "passive"))
    (pad "2" smd roundrect (at 0.485 0) (size 0.59 0.64) (layers "F.Cu" "F.Paste" "F.Mask") (roundrect_rratio 0.25)
      (net 357 "SDA_3V3") (pintype "passive"))
  )
	(footprint "data-center-rdimm-ddr4-tester-footprints:R_0402_1005Metric" (layer "F.Cu")
    (at 117.336328 63.160008 180)
    (descr "Resistor SMD 0402")
    (tags "resistor SMD 0402")
    (property "Author" "Antmicro")
    (property "Current" "1A")
    (property "DNP" "DNP")
    (property "License" "Apache-2.0")
    (property "MPN" "ERJ2GE0R00X")
    (property "Manufacturer" "Panasonic")
    (property "Sheetfile" "fpga-banks-16-34.kicad_sch")
    (property "Sheetname" "FPGA banks 16-34")
    (property "Tolerance" "")
    (property "Val" "0R")
    (property "dnp" "")
    (property "exclude_from_bom" "")
    (property "ki_description" "0R resistor in 0402 package with unspecified tolerance")
    (attr exclude_from_pos_files exclude_from_bom)
    (fp_text reference "R164" (at -0.813672 -0.349992 180) (layer "F.SilkS")
        (effects (font (size 0.7 0.7) (thickness 0.15)) (justify left bottom))
    )
    (fp_text value "R_0R_0402" (at 0 1.4 180) (layer "F.Fab") hide
        (effects (font (size 0.7 0.7) (thickness 0.15)) (justify left bottom))
    )
    (fp_text user "License: Apache-2.0" (at -0.95 5.169 180) (layer "F.Fab") hide
        (effects (font (size 0.7 0.7) (thickness 0.15)) (justify left bottom))
    )
    (fp_text user "${REFERENCE}" (at -0.95 3.168 180) (layer "F.Fab") hide
        (effects (font (size 0.7 0.7) (thickness 0.15)) (justify left bottom))
    )
    (fp_text user "Author: Antmicro" (at -0.95 4.169 180) (layer "F.Fab") hide
        (effects (font (size 0.7 0.7) (thickness 0.15)) (justify left bottom))
    )
    (fp_rect (start -0.93 -0.47) (end 0.93 0.47)
      (stroke (width 0.05) (type solid)) (fill none) (layer "F.CrtYd"))
    (fp_rect (start -0.5 -0.25) (end 0.5 0.25)
      (stroke (width 0.15) (type solid)) (fill none) (layer "F.Fab"))
    (pad "1" smd roundrect (at -0.485 0 180) (size 0.59 0.64) (layers "F.Cu" "F.Paste" "F.Mask") (roundrect_rratio 0.25)
      (net 185 "VDDSPD") (pintype "passive"))
    (pad "2" smd roundrect (at 0.485 0 180) (size 0.59 0.64) (layers "F.Cu" "F.Paste" "F.Mask") (roundrect_rratio 0.25)
      (net 195 "SA2") (pintype "passive"))
  )
	(footprint "data-center-rdimm-ddr4-tester-footprints:R_0402_1005Metric" (layer "F.Cu")
    (at 112.336328 65.160008 180)
    (descr "Resistor SMD 0402")
    (tags "resistor SMD 0402")
    (property "Author" "Antmicro")
    (property "Current" "1A")
    (property "License" "Apache-2.0")
    (property "MPN" "ERJ2GE0R00X")
    (property "Manufacturer" "Panasonic")
    (property "Sheetfile" "fpga-banks-16-34.kicad_sch")
    (property "Sheetname" "FPGA banks 16-34")
    (property "Tolerance" "")
    (property "Val" "0R")
    (property "ki_description" "0R resistor in 0402 package with unspecified tolerance")
    (attr smd)
    (fp_text reference "R169" (at 4.126328 -0.369992 180) (layer "F.SilkS")
        (effects (font (size 0.7 0.7) (thickness 0.15)) (justify left bottom))
    )
    (fp_text value "R_0R_0402" (at 0 1.4 180) (layer "F.Fab") hide
        (effects (font (size 0.7 0.7) (thickness 0.15)) (justify left bottom))
    )
    (fp_text user "License: Apache-2.0" (at -0.95 5.169 180) (layer "F.Fab") hide
        (effects (font (size 0.7 0.7) (thickness 0.15)) (justify left bottom))
    )
    (fp_text user "Author: Antmicro" (at -0.95 4.169 180) (layer "F.Fab") hide
        (effects (font (size 0.7 0.7) (thickness 0.15)) (justify left bottom))
    )
    (fp_text user "${REFERENCE}" (at -0.95 3.168 180) (layer "F.Fab") hide
        (effects (font (size 0.7 0.7) (thickness 0.15)) (justify left bottom))
    )
    (fp_rect (start -0.93 -0.47) (end 0.93 0.47)
      (stroke (width 0.05) (type solid)) (fill none) (layer "F.CrtYd"))
    (fp_rect (start -0.5 -0.25) (end 0.5 0.25)
      (stroke (width 0.15) (type solid)) (fill none) (layer "F.Fab"))
    (pad "1" smd roundrect (at -0.485 0 180) (size 0.59 0.64) (layers "F.Cu" "F.Paste" "F.Mask") (roundrect_rratio 0.25)
      (net 218 "SA0") (pintype "passive"))
    (pad "2" smd roundrect (at 0.485 0 180) (size 0.59 0.64) (layers "F.Cu" "F.Paste" "F.Mask") (roundrect_rratio 0.25)
      (net 9 "GND") (pintype "passive"))
  )
	(footprint "data-center-rdimm-ddr4-tester-footprints:R_0402_1005Metric" (layer "F.Cu")
    (at 112.336328 63.160008 180)
    (descr "Resistor SMD 0402")
    (tags "resistor SMD 0402")
    (property "Author" "Antmicro")
    (property "Current" "1A")
    (property "License" "Apache-2.0")
    (property "MPN" "ERJ2GE0R00X")
    (property "Manufacturer" "Panasonic")
    (property "Sheetfile" "fpga-banks-16-34.kicad_sch")
    (property "Sheetname" "FPGA banks 16-34")
    (property "Tolerance" "")
    (property "Val" "0R")
    (property "ki_description" "0R resistor in 0402 package with unspecified tolerance")
    (attr smd)
    (fp_text reference "R165" (at 4.126328 -0.369992 180) (layer "F.SilkS")
        (effects (font (size 0.7 0.7) (thickness 0.15)) (justify left bottom))
    )
    (fp_text value "R_0R_0402" (at 0 1.4 180) (layer "F.Fab") hide
        (effects (font (size 0.7 0.7) (thickness 0.15)) (justify left bottom))
    )
    (fp_text user "License: Apache-2.0" (at -0.95 5.169 180) (layer "F.Fab") hide
        (effects (font (size 0.7 0.7) (thickness 0.15)) (justify left bottom))
    )
    (fp_text user "Author: Antmicro" (at -0.95 4.169 180) (layer "F.Fab") hide
        (effects (font (size 0.7 0.7) (thickness 0.15)) (justify left bottom))
    )
    (fp_text user "${REFERENCE}" (at -0.95 3.168 180) (layer "F.Fab") hide
        (effects (font (size 0.7 0.7) (thickness 0.15)) (justify left bottom))
    )
    (fp_rect (start -0.93 -0.47) (end 0.93 0.47)
      (stroke (width 0.05) (type solid)) (fill none) (layer "F.CrtYd"))
    (fp_rect (start -0.5 -0.25) (end 0.5 0.25)
      (stroke (width 0.15) (type solid)) (fill none) (layer "F.Fab"))
    (pad "1" smd roundrect (at -0.485 0 180) (size 0.59 0.64) (layers "F.Cu" "F.Paste" "F.Mask") (roundrect_rratio 0.25)
      (net 195 "SA2") (pintype "passive"))
    (pad "2" smd roundrect (at 0.485 0 180) (size 0.59 0.64) (layers "F.Cu" "F.Paste" "F.Mask") (roundrect_rratio 0.25)
      (net 9 "GND") (pintype "passive"))
  )
	(footprint "data-center-rdimm-ddr4-tester-footprints:R_0402_1005Metric" (layer "F.Cu")
    (at 112.336328 64.160008 180)
    (descr "Resistor SMD 0402")
    (tags "resistor SMD 0402")
    (property "Author" "Antmicro")
    (property "Current" "1A")
    (property "License" "Apache-2.0")
    (property "MPN" "ERJ2GE0R00X")
    (property "Manufacturer" "Panasonic")
    (property "Sheetfile" "fpga-banks-16-34.kicad_sch")
    (property "Sheetname" "FPGA banks 16-34")
    (property "Tolerance" "")
    (property "Val" "0R")
    (property "ki_description" "0R resistor in 0402 package with unspecified tolerance")
    (attr smd)
    (fp_text reference "R167" (at 4.126328 -0.369992 180) (layer "F.SilkS")
        (effects (font (size 0.7 0.7) (thickness 0.15)) (justify left bottom))
    )
    (fp_text value "R_0R_0402" (at 0 1.4 180) (layer "F.Fab") hide
        (effects (font (size 0.7 0.7) (thickness 0.15)) (justify left bottom))
    )
    (fp_text user "Author: Antmicro" (at -0.95 4.169 180) (layer "F.Fab") hide
        (effects (font (size 0.7 0.7) (thickness 0.15)) (justify left bottom))
    )
    (fp_text user "${REFERENCE}" (at -0.95 3.168 180) (layer "F.Fab") hide
        (effects (font (size 0.7 0.7) (thickness 0.15)) (justify left bottom))
    )
    (fp_text user "License: Apache-2.0" (at -0.95 5.169 180) (layer "F.Fab") hide
        (effects (font (size 0.7 0.7) (thickness 0.15)) (justify left bottom))
    )
    (fp_rect (start -0.93 -0.47) (end 0.93 0.47)
      (stroke (width 0.05) (type solid)) (fill none) (layer "F.CrtYd"))
    (fp_rect (start -0.5 -0.25) (end 0.5 0.25)
      (stroke (width 0.15) (type solid)) (fill none) (layer "F.Fab"))
    (pad "1" smd roundrect (at -0.485 0 180) (size 0.59 0.64) (layers "F.Cu" "F.Paste" "F.Mask") (roundrect_rratio 0.25)
      (net 214 "SA1") (pintype "passive"))
    (pad "2" smd roundrect (at 0.485 0 180) (size 0.59 0.64) (layers "F.Cu" "F.Paste" "F.Mask") (roundrect_rratio 0.25)
      (net 9 "GND") (pintype "passive"))
  )
	(footprint "data-center-rdimm-ddr4-tester-footprints:R_0402_1005Metric" (layer "F.Cu")
    (at 177.04 63.055 90)
    (descr "Resistor SMD 0402")
    (tags "resistor SMD 0402")
    (property "Author" "Antmicro")
    (property "License" "Apache-2.0")
    (property "MPN" "CR0402-FX-4701GLF")
    (property "Manufacturer" "Bourns")
    (property "Sheetfile" "fpga-banks-16-34.kicad_sch")
    (property "Sheetname" "FPGA banks 16-34")
    (property "Tolerance" "1%")
    (property "Val" "4k7")
    (property "ki_description" "4k7 resistor in 0402 package with 1% tolerance")
    (attr smd)
    (fp_text reference "R170" (at -3.715 0.37 90) (layer "F.SilkS")
        (effects (font (size 0.7 0.7) (thickness 0.15)) (justify left bottom))
    )
    (fp_text value "R_4k7_0402" (at 0 1.4 90) (layer "F.Fab") hide
        (effects (font (size 0.7 0.7) (thickness 0.15)) (justify left bottom))
    )
    (fp_text user "Author: Antmicro" (at -0.95 4.169 90) (layer "F.Fab") hide
        (effects (font (size 0.7 0.7) (thickness 0.15)) (justify left bottom))
    )
    (fp_text user "License: Apache-2.0" (at -0.95 5.169 90) (layer "F.Fab") hide
        (effects (font (size 0.7 0.7) (thickness 0.15)) (justify left bottom))
    )
    (fp_text user "${REFERENCE}" (at -0.95 3.168 90) (layer "F.Fab") hide
        (effects (font (size 0.7 0.7) (thickness 0.15)) (justify left bottom))
    )
    (fp_rect (start -0.93 -0.47) (end 0.93 0.47)
      (stroke (width 0.05) (type solid)) (fill none) (layer "F.CrtYd"))
    (fp_rect (start -0.5 -0.25) (end 0.5 0.25)
      (stroke (width 0.15) (type solid)) (fill none) (layer "F.Fab"))
    (pad "1" smd roundrect (at -0.485 0 90) (size 0.59 0.64) (layers "F.Cu" "F.Paste" "F.Mask") (roundrect_rratio 0.25)
      (net 77 "VDDQ") (pintype "passive"))
    (pad "2" smd roundrect (at 0.485 0 90) (size 0.59 0.64) (layers "F.Cu" "F.Paste" "F.Mask") (roundrect_rratio 0.25)
      (net 187 "~{EVENT}") (pintype "passive"))
  )
	(footprint "data-center-rdimm-ddr4-tester-footprints:WSON-8_6x8x0.5mm_P1.27mm" (layer "F.Cu")
    (at 230.052 117.636)
    (property "Author" "Antmicro")
    (property "License" "Apache-2.0")
    (property "MPN" "S25FL128SAGNFI000")
    (property "Manufacturer" "Cypress Semiconductor")
    (property "Sheetfile" "config-spi.kicad_sch")
    (property "Sheetname" "Config SPI flash")
    (property "ki_description" "28 Mbit (16 Mbyte)/256 Mbit (32 Mbyte), 3.0V SPI Flash Memory")
    (property "ki_keywords" "28 Mbit (16 Mbyte)/256 Mbit (32 Mbyte), 3.0V SPI Flash Memory")
    (attr smd)
    (fp_text reference "U3" (at 0 -3.6) (layer "F.SilkS")
        (effects (font (size 0.7 0.7) (thickness 0.15)) (justify left bottom))
    )
    (fp_text value "S25FL128SAGNFI000" (at 0 4.3) (layer "F.Fab") hide
        (effects (font (size 0.7 0.7) (thickness 0.15)) (justify left bottom))
    )
    (fp_text user "${REFERENCE}" (at 0 10.903) (layer "F.Fab") hide
        (effects (font (size 0.7 0.7) (thickness 0.15)) (justify left bottom))
    )
    (fp_text user "Author: Antmicro" (at 0 12.104) (layer "F.Fab") hide
        (effects (font (size 0.7 0.7) (thickness 0.15)) (justify left bottom))
    )
    (fp_text user "License: Apache-2.0" (at 0 13.303) (layer "F.Fab") hide
        (effects (font (size 0.7 0.7) (thickness 0.15)) (justify left bottom))
    )
    (fp_line (start 4 -3.2) (end -3.975 -3.2)
      (stroke (width 0.15) (type solid)) (layer "F.SilkS"))
    (fp_line (start 4.0005 3.2) (end -3.9995 3.2)
      (stroke (width 0.15) (type solid)) (layer "F.SilkS"))
    (fp_circle (center -4.2 -2.4) (end -4.149 -2.4)
      (stroke (width 0.15) (type solid)) (fill solid) (layer "F.SilkS"))
    (fp_rect (start -4.7 -3.25) (end 4.7 3.25)
      (stroke (width 0.05) (type solid)) (fill none) (layer "F.CrtYd"))
    (fp_line (start -3.9995 3.0005) (end -3.9995 -1.9995)
      (stroke (width 0.15) (type solid)) (layer "F.Fab"))
    (fp_line (start -3.0015 -2.9995) (end -3.9995 -1.9995)
      (stroke (width 0.15) (type solid)) (layer "F.Fab"))
    (fp_line (start -3.0015 -2.9995) (end 3.9995 -2.9995)
      (stroke (width 0.15) (type solid)) (layer "F.Fab"))
    (fp_line (start 3.9995 -2.9995) (end 3.9995 3.0005)
      (stroke (width 0.15) (type solid)) (layer "F.Fab"))
    (fp_line (start 3.9995 3.0005) (end -3.9995 3.0005)
      (stroke (width 0.15) (type solid)) (layer "F.Fab"))
    (pad "1" smd roundrect (at -3.9995 -1.9045 270) (size 0.4 1.3) (layers "F.Cu" "F.Paste" "F.Mask") (roundrect_rratio 0.25)
      (net 596 "Net-(U3-~{CS})") (pinfunction "~{CS}") (pintype "input"))
    (pad "2" smd roundrect (at -3.9995 -0.6355 270) (size 0.4 1.3) (layers "F.Cu" "F.Paste" "F.Mask") (roundrect_rratio 0.25)
      (net 651 "Net-(U3-SO{slash}IO1)") (pinfunction "SO/IO1") (pintype "bidirectional"))
    (pad "3" smd roundrect (at -3.9995 0.6345 270) (size 0.4 1.3) (layers "F.Cu" "F.Paste" "F.Mask") (roundrect_rratio 0.25)
      (net 600 "Net-(U3-~{WP}{slash}IO2)") (pinfunction "~{WP}/IO2") (pintype "bidirectional"))
    (pad "4" smd roundrect (at -3.9995 1.9045 270) (size 0.4 1.3) (layers "F.Cu" "F.Paste" "F.Mask") (roundrect_rratio 0.25)
      (net 9 "GND") (pinfunction "V_{SS}") (pintype "power_in"))
    (pad "5" smd roundrect (at 3.9995 1.8755 270) (size 0.4 1.3) (layers "F.Cu" "F.Paste" "F.Mask") (roundrect_rratio 0.25)
      (net 650 "Net-(U3-SI{slash}IO0)") (pinfunction "SI/IO0") (pintype "bidirectional"))
    (pad "6" smd roundrect (at 3.9995 0.6035 270) (size 0.4 1.3) (layers "F.Cu" "F.Paste" "F.Mask") (roundrect_rratio 0.25)
      (net 597 "Net-(U3-SCK)") (pinfunction "SCK") (pintype "input"))
    (pad "7" smd roundrect (at 3.9995 -0.6655 270) (size 0.4 1.3) (layers "F.Cu" "F.Paste" "F.Mask") (roundrect_rratio 0.25)
      (net 599 "Net-(U3-~{HOLD}{slash}IO3)") (pinfunction "~{HOLD}/IO3") (pintype "bidirectional"))
    (pad "8" smd roundrect (at 3.9995 -1.9355 270) (size 0.4 1.3) (layers "F.Cu" "F.Paste" "F.Mask") (roundrect_rratio 0.25)
      (net 143 "3V3_SYS") (pinfunction "V_{CC}") (pintype "power_in"))
    (pad "9" smd roundrect (at -0.0005 -0.0005) (size 4.8 4.65) (layers "F.Cu" "F.Paste" "F.Mask") (roundrect_rratio 0.05)
      (chamfer_ratio 0.1) (chamfer top_left)
      (net 667 "unconnected-(U3-EP-Pad9)") (pinfunction "EP") (pintype "no_connect"))
  )
	(footprint "data-center-rdimm-ddr4-tester-footprints:R_0402_1005Metric" (layer "F.Cu")
    (at 145.046328 114.597157 90)
    (descr "Resistor SMD 0402")
    (tags "resistor SMD 0402")
    (property "Author" "Antmicro")
    (property "License" "Apache-2.0")
    (property "MPN" "CR0402-FX-1002GLF")
    (property "Manufacturer" "Bourns")
    (property "Sheetfile" "interfaces.kicad_sch")
    (property "Sheetname" "Interfaces")
    (property "Tolerance" "1%")
    (property "Val" "10k")
    (property "ki_description" "10k resistor in 0402 package with 1% tolerance")
    (attr smd)
    (fp_text reference "R130" (at -1.362843 -0.566328 90) (layer "F.SilkS")
        (effects (font (size 0.7 0.7) (thickness 0.15)) (justify left bottom))
    )
    (fp_text value "R_10k_0402" (at 0 1.4 90) (layer "F.Fab") hide
        (effects (font (size 0.7 0.7) (thickness 0.15)) (justify left bottom))
    )
    (fp_text user "${REFERENCE}" (at -0.95 3.168 90) (layer "F.Fab") hide
        (effects (font (size 0.7 0.7) (thickness 0.15)) (justify left bottom))
    )
    (fp_text user "Author: Antmicro" (at -0.95 4.169 90) (layer "F.Fab") hide
        (effects (font (size 0.7 0.7) (thickness 0.15)) (justify left bottom))
    )
    (fp_text user "License: Apache-2.0" (at -0.95 5.169 90) (layer "F.Fab") hide
        (effects (font (size 0.7 0.7) (thickness 0.15)) (justify left bottom))
    )
    (fp_rect (start -0.93 -0.47) (end 0.93 0.47)
      (stroke (width 0.05) (type solid)) (fill none) (layer "F.CrtYd"))
    (fp_rect (start -0.5 -0.25) (end 0.5 0.25)
      (stroke (width 0.15) (type solid)) (fill none) (layer "F.Fab"))
    (pad "1" smd roundrect (at -0.485 0 90) (size 0.59 0.64) (layers "F.Cu" "F.Paste" "F.Mask") (roundrect_rratio 0.25)
      (net 143 "3V3_SYS") (pintype "passive"))
    (pad "2" smd roundrect (at 0.485 0 90) (size 0.59 0.64) (layers "F.Cu" "F.Paste" "F.Mask") (roundrect_rratio 0.25)
      (net 657 "Net-(U7-~{RESET})") (pintype "passive"))
  )
)
